#ISCELL
  pure_quanta quanta_title_block_c *
  *
#ISCELL
  standard offpage *
  page27_i1
#ISCELL
  standard offpage *
  page27_i10
#ISCELL
  standard tap *
  page27_i100
#ISCELL
  standard tap *
  page27_i101
#ISCELL
  standard tap *
  page27_i102
#ISCELL
  standard tap *
  page27_i103
#ISCELL
  standard tap *
  page27_i104
#ISCELL
  standard tap *
  page27_i105
#ISCELL
  standard tap *
  page27_i106
#ISCELL
  standard tap *
  page27_i107
#ISCELL
  standard tap *
  page27_i108
#ISCELL
  standard tap *
  page27_i109
#ISCELL
  standard offpage *
  page27_i11
#ISCELL
  standard tap *
  page27_i110
#ISCELL
  standard tap *
  page27_i111
#ISCELL
  standard tap *
  page27_i112
#ISCELL
  standard tap *
  page27_i113
#ISCELL
  standard tap *
  page27_i114
#ISCELL
  standard tap *
  page27_i115
#ISCELL
  standard tap *
  page27_i116
#ISCELL
  standard tap *
  page27_i117
#ISCELL
  standard tap *
  page27_i118
#ISCELL
  standard tap *
  page27_i119
#ISCELL
  standard tap *
  page27_i12
#ISCELL
  standard tap *
  page27_i120
#ISCELL
  standard tap *
  page27_i121
#ISCELL
  standard tap *
  page27_i122
#ISCELL
  standard tap *
  page27_i123
#ISCELL
  standard tap *
  page27_i124
#ISCELL
  standard tap *
  page27_i125
#ISCELL
  standard tap *
  page27_i126
#ISCELL
  standard tap *
  page27_i127
#ISCELL
  standard tap *
  page27_i128
#ISCELL
  standard tap *
  page27_i129
#ISCELL
  standard tap *
  page27_i13
#ISCELL
  standard tap *
  page27_i130
#ISCELL
  standard tap *
  page27_i131
#ISCELL
  standard tap *
  page27_i132
#ISCELL
  standard tap *
  page27_i133
#ISCELL
  standard tap *
  page27_i134
#ISCELL
  standard tap *
  page27_i135
#ISCELL
  standard tap *
  page27_i136
#ISCELL
  standard tap *
  page27_i137
#ISCELL
  standard tap *
  page27_i138
#ISCELL
  standard tap *
  page27_i139
#ISCELL
  standard tap *
  page27_i14
#ISCELL
  standard tap *
  page27_i140
#ISCELL
  standard tap *
  page27_i141
#ISCELL
  standard tap *
  page27_i142
#ISCELL
  standard tap *
  page27_i143
#ISCELL
  standard tap *
  page27_i144
#ISCELL
  standard tap *
  page27_i145
#ISCELL
  standard tap *
  page27_i146
#ISCELL
  standard tap *
  page27_i147
#ISCELL
  standard tap *
  page27_i148
#ISCELL
  standard tap *
  page27_i149
#ISCELL
  standard tap *
  page27_i15
#ISCELL
  standard tap *
  page27_i150
#ISCELL
  standard tap *
  page27_i151
#ISCELL
  standard tap *
  page27_i152
#ISCELL
  standard tap *
  page27_i153
#ISCELL
  standard tap *
  page27_i154
#ISCELL
  standard tap *
  page27_i155
#ISCELL
  standard tap *
  page27_i156
#ISCELL
  standard tap *
  page27_i157
#ISCELL
  standard tap *
  page27_i158
#ISCELL
  standard offpage *
  page27_i159
#ISCELL
  standard tap *
  page27_i16
#ISCELL
  standard offpage *
  page27_i160
#ISCELL
  standard offpage *
  page27_i161
#ISCELL
  standard offpage *
  page27_i162
#ISCELL
  standard offpage *
  page27_i163
#ISCELL
  standard offpage *
  page27_i164
#ISCELL
  standard offpage *
  page27_i165
#ISCELL
  standard offpage *
  page27_i166
#ISCELL
  standard offpage *
  page27_i167
#ISCELL
  standard offpage *
  page27_i168
#CELL
  pure_quanta socket4677_azif0045p001c01cs *
  page27_i169
#ISCELL
  standard tap *
  page27_i17
#ISCELL
  standard tap *
  page27_i18
#ISCELL
  standard tap *
  page27_i19
#ISCELL
  standard offpage *
  page27_i2
#ISCELL
  standard tap *
  page27_i20
#ISCELL
  standard tap *
  page27_i21
#ISCELL
  standard tap *
  page27_i22
#ISCELL
  standard tap *
  page27_i23
#ISCELL
  standard tap *
  page27_i24
#ISCELL
  standard tap *
  page27_i25
#ISCELL
  standard tap *
  page27_i26
#ISCELL
  standard tap *
  page27_i27
#ISCELL
  standard tap *
  page27_i28
#ISCELL
  standard tap *
  page27_i29
#ISCELL
  standard tap *
  page27_i3
#ISCELL
  standard tap *
  page27_i30
#ISCELL
  standard tap *
  page27_i31
#ISCELL
  standard tap *
  page27_i32
#ISCELL
  standard tap *
  page27_i33
#ISCELL
  standard tap *
  page27_i34
#ISCELL
  standard tap *
  page27_i35
#ISCELL
  standard tap *
  page27_i36
#ISCELL
  standard tap *
  page27_i37
#ISCELL
  standard tap *
  page27_i38
#ISCELL
  standard tap *
  page27_i39
#ISCELL
  standard tap *
  page27_i4
#ISCELL
  standard tap *
  page27_i40
#ISCELL
  standard tap *
  page27_i41
#ISCELL
  standard tap *
  page27_i42
#ISCELL
  standard tap *
  page27_i43
#ISCELL
  standard tap *
  page27_i44
#ISCELL
  standard tap *
  page27_i45
#ISCELL
  standard tap *
  page27_i46
#ISCELL
  standard tap *
  page27_i47
#ISCELL
  standard tap *
  page27_i48
#ISCELL
  standard tap *
  page27_i49
#ISCELL
  standard tap *
  page27_i5
#ISCELL
  standard tap *
  page27_i50
#ISCELL
  standard tap *
  page27_i51
#ISCELL
  standard offpage *
  page27_i52
#ISCELL
  standard offpage *
  page27_i53
#ISCELL
  standard tap *
  page27_i54
#ISCELL
  standard tap *
  page27_i55
#ISCELL
  standard tap *
  page27_i56
#ISCELL
  standard tap *
  page27_i57
#ISCELL
  standard tap *
  page27_i58
#ISCELL
  standard tap *
  page27_i59
#ISCELL
  standard tap *
  page27_i6
#ISCELL
  standard tap *
  page27_i60
#ISCELL
  standard tap *
  page27_i61
#ISCELL
  standard tap *
  page27_i62
#ISCELL
  standard tap *
  page27_i63
#ISCELL
  standard tap *
  page27_i64
#ISCELL
  standard tap *
  page27_i65
#ISCELL
  standard tap *
  page27_i66
#ISCELL
  standard tap *
  page27_i67
#ISCELL
  standard tap *
  page27_i68
#ISCELL
  standard tap *
  page27_i69
#ISCELL
  standard tap *
  page27_i7
#ISCELL
  standard tap *
  page27_i70
#ISCELL
  standard tap *
  page27_i71
#ISCELL
  standard tap *
  page27_i72
#ISCELL
  standard tap *
  page27_i73
#ISCELL
  standard tap *
  page27_i74
#ISCELL
  standard tap *
  page27_i75
#ISCELL
  standard tap *
  page27_i76
#ISCELL
  standard tap *
  page27_i77
#ISCELL
  standard tap *
  page27_i78
#ISCELL
  standard tap *
  page27_i79
#ISCELL
  standard tap *
  page27_i8
#ISCELL
  standard tap *
  page27_i80
#ISCELL
  standard tap *
  page27_i81
#ISCELL
  standard tap *
  page27_i82
#ISCELL
  standard tap *
  page27_i83
#ISCELL
  standard tap *
  page27_i84
#ISCELL
  standard tap *
  page27_i85
#ISCELL
  standard tap *
  page27_i86
#ISCELL
  standard tap *
  page27_i87
#ISCELL
  standard tap *
  page27_i88
#ISCELL
  standard tap *
  page27_i89
#ISCELL
  standard tap *
  page27_i9
#ISCELL
  standard tap *
  page27_i90
#ISCELL
  standard offpage *
  page27_i92
#ISCELL
  standard offpage *
  page27_i93
#ISCELL
  standard offpage *
  page27_i94
#ISCELL
  standard offpage *
  page27_i95
#ISCELL
  standard offpage *
  page27_i96
#ISCELL
  standard tap *
  page27_i97
#ISCELL
  standard tap *
  page27_i98
#ISCELL
  standard tap *
  page27_i99
